# T6G (Grand Teton) — schematic netlist excerpt (pin names and nets, part order shuffled) for the footprints in the layout excerpt that follows; sources: Cadence DE-HDL packaged netlist, KiCad conversion of 04192023_DAF0TMB3IC0_F0TG_MB_C_brd_V02_OCP.brd

U256  74LVC2G17GW  IC  pkg SOT363  page 128
  A0  = RST_PERST_CPU0_SWB_R_N
  GND  = GND
  A1  = FM_SWB_PWR_EN_R
  B1  = FM_SWB_PWR_EN_R1_BUF
  VCC  = P3V3_AUX
  B0  = RST_PERST_1_SWB_BUF_R_N

PC181  Q_CAP  560PF 50V 10% EMPTY  pkg C0402  page 195 : A = SW_PVDDCR_CPU0_P0_SW4 ; B = SW_PVDDCR_CPU0_P0_SW4_RC

(kicad_pcb
	(version 20260206)
	(generator "pcbnew")
	(generator_version "10.0")
	(general
		(thickness 1.6)
		(legacy_teardrops no)
	)
	(paper "A4")
	(title_block
		(title "04192023_DAF0TMB3IC0_F0TG_MB_C_brd_V02_OCP.brd")
		(comment 1 "Grand Teton / footprints 873-874 of 8354")
	)
	(layers
		(0 "F.Cu" signal "TOP")
		(4 "In1.Cu" signal "GND")
		(6 "In2.Cu" signal "IN1")
		(8 "In3.Cu" signal "GND1")
		(10 "In4.Cu" signal "IN2")
		(12 "In5.Cu" signal "GND2")
		(14 "In6.Cu" signal "IN3")
		(16 "In7.Cu" signal "GND3")
		(18 "In8.Cu" signal "VCC")
		(20 "In9.Cu" signal "VCC1")
		(22 "In10.Cu" signal "GND4")
		(24 "In11.Cu" signal "IN4")
		(26 "In12.Cu" signal "GND5")
		(28 "In13.Cu" signal "IN5")
		(30 "In14.Cu" signal "GND6")
		(32 "In15.Cu" signal "IN6")
		(34 "In16.Cu" signal "GND7")
		(2 "B.Cu" signal "BOTTOM")
		(9 "F.Adhes" user "F.Adhesive")
		(11 "B.Adhes" user "B.Adhesive")
		(13 "F.Paste" user "Package Geometry/Pastemask Top")
		(15 "B.Paste" user "Package Geometry/Pastemask Bottom")
		(5 "F.SilkS" user "Ref Des/Silkscreen Top")
		(7 "B.SilkS" user "Ref Des/Silkscreen Bottom")
		(1 "F.Mask" user "Board Geometry/Soldermask Top")
		(3 "B.Mask" user "Board Geometry/Soldermask Bottom")
		(17 "Dwgs.User" user "User.Drawings")
		(19 "Cmts.User" user "User.Comments")
		(21 "Eco1.User" user "User.Eco1")
		(23 "Eco2.User" user "User.Eco2")
		(25 "Edge.Cuts" user "Board Geometry/Outline")
		(27 "Margin" user)
		(31 "F.CrtYd" user "Package Geometry/Place Bound Top")
		(29 "B.CrtYd" user "Package Geometry/Place Bound Bottom")
		(35 "F.Fab" user "Ref Des/Assembly Top")
		(33 "B.Fab" user "Ref Des/Assembly Bottom")
	)
	(footprint ""
		(layer "F.Cu")
		(at 40.386 -436.499)
		(property "Reference" "U256"
			(at -0.413004 -3.526282 0)
			(unlocked yes)
			(layer "F.SilkS")
			(effects
				(font
					(size 0.7874 0.5842)
					(thickness 0.1524)
				)
				(justify left)
			)
		)
		(property "Value" ""
			(at 0 0 0)
			(layer "F.Fab")
			(effects
				(font
					(size 1.27 1.27)
				)
			)
		)
		(duplicate_pad_numbers_are_jumpers no)
		(fp_line
			(start -1.3462 -1.100074)
			(end -0.670052 -1.100074)
			(stroke
				(width 0.1524)
				(type default)
			)
			(layer "F.SilkS")
		)
		(fp_line
			(start -1.3462 1.100074)
			(end -1.3462 -1.100074)
			(stroke
				(width 0.1524)
				(type default)
			)
			(layer "F.SilkS")
		)
		(fp_line
			(start -0.670052 -1.100074)
			(end 0 -0.381)
			(stroke
				(width 0.1524)
				(type default)
			)
			(layer "F.SilkS")
		)
		(fp_line
			(start 0 -0.381)
			(end 0.670052 -1.100074)
			(stroke
				(width 0.1524)
				(type default)
			)
			(layer "F.SilkS")
		)
		(fp_line
			(start 0.670052 -1.100074)
			(end 1.3462 -1.100074)
			(stroke
				(width 0.1524)
				(type default)
			)
			(layer "F.SilkS")
		)
		(fp_line
			(start 1.3462 -1.100074)
			(end 1.3462 1.100074)
			(stroke
				(width 0.1524)
				(type default)
			)
			(layer "F.SilkS")
		)
		(fp_line
			(start 1.3462 1.100074)
			(end -1.3462 1.100074)
			(stroke
				(width 0.1524)
				(type default)
			)
			(layer "F.SilkS")
		)
		(fp_poly
			(pts
				(xy -2.620518 -1.867408) (xy -2.160778 -2.474976) (xy -1.78308 -1.711198)
			)
			(stroke
				(width 0)
				(type default)
			)
			(fill yes)
			(layer "F.SilkS")
		)
		(fp_line
			(start -1.100074 -0.8001)
			(end -0.670052 -0.8001)
			(stroke
				(width 0.1)
				(type default)
			)
			(layer "F.Fab")
		)
		(fp_line
			(start -1.100074 0.8001)
			(end -1.100074 -0.8001)
			(stroke
				(width 0.1)
				(type default)
			)
			(layer "F.Fab")
		)
		(fp_line
			(start -0.670052 -1.100074)
			(end 0.670052 -1.100074)
			(stroke
				(width 0.1)
				(type default)
			)
			(layer "F.Fab")
		)
		(fp_line
			(start -0.670052 -0.8001)
			(end -0.670052 -1.100074)
			(stroke
				(width 0.1)
				(type default)
			)
			(layer "F.Fab")
		)
		(fp_line
			(start -0.670052 0.8001)
			(end -1.100074 0.8001)
			(stroke
				(width 0.1)
				(type default)
			)
			(layer "F.Fab")
		)
		(fp_line
			(start -0.670052 0.8001)
			(end -0.670052 -0.8001)
			(stroke
				(width 0.1)
				(type default)
			)
			(layer "F.Fab")
		)
		(fp_line
			(start -0.670052 1.100074)
			(end -0.670052 0.8001)
			(stroke
				(width 0.1)
				(type default)
			)
			(layer "F.Fab")
		)
		(fp_line
			(start 0.670052 -1.100074)
			(end 0.670052 -0.8001)
			(stroke
				(width 0.1)
				(type default)
			)
			(layer "F.Fab")
		)
		(fp_line
			(start 0.670052 -0.8001)
			(end 0.670052 0.8001)
			(stroke
				(width 0.1)
				(type default)
			)
			(layer "F.Fab")
		)
		(fp_line
			(start 0.670052 -0.8001)
			(end 1.100074 -0.8001)
			(stroke
				(width 0.1)
				(type default)
			)
			(layer "F.Fab")
		)
		(fp_line
			(start 0.670052 0.8001)
			(end 0.670052 1.100074)
			(stroke
				(width 0.1)
				(type default)
			)
			(layer "F.Fab")
		)
		(fp_line
			(start 0.670052 1.100074)
			(end -0.670052 1.100074)
			(stroke
				(width 0.1)
				(type default)
			)
			(layer "F.Fab")
		)
		(fp_line
			(start 1.100074 -0.8001)
			(end 1.100074 0.8001)
			(stroke
				(width 0.1)
				(type default)
			)
			(layer "F.Fab")
		)
		(fp_line
			(start 1.100074 0.8001)
			(end 0.670052 0.8001)
			(stroke
				(width 0.1)
				(type default)
			)
			(layer "F.Fab")
		)
		(fp_poly
			(pts
				(xy -1.524 -0.649986) (xy -2.286 -1.030986) (xy -2.286 -0.268986)
			)
			(stroke
				(width 0)
				(type default)
			)
			(fill yes)
			(layer "F.Fab")
		)
		(pad "1" smd rect
			(at -0.94996 -0.649986 270)
			(size 0.4064 0.508)
			(layers "F.Cu" "F.Mask" "F.Paste")
			(net "RST_PERST_CPU0_SWB_R_N")
		)
		(pad "2" smd rect
			(at -0.94996 0 270)
			(size 0.4064 0.508)
			(layers "F.Cu" "F.Mask" "F.Paste")
			(net "GND")
		)
		(pad "3" smd rect
			(at -0.94996 0.649986 270)
			(size 0.4064 0.508)
			(layers "F.Cu" "F.Mask" "F.Paste")
			(net "FM_SWB_PWR_EN_R")
		)
		(pad "4" smd rect
			(at 0.94996 0.649986 270)
			(size 0.4064 0.508)
			(layers "F.Cu" "F.Mask" "F.Paste")
			(net "FM_SWB_PWR_EN_R1_BUF")
		)
		(pad "5" smd rect
			(at 0.94996 0 270)
			(size 0.4064 0.508)
			(layers "F.Cu" "F.Mask" "F.Paste")
			(net "P3V3_AUX")
		)
		(pad "6" smd rect
			(at 0.94996 -0.649986 270)
			(size 0.4064 0.508)
			(layers "F.Cu" "F.Mask" "F.Paste")
			(net "RST_PERST_1_SWB_BUF_R_N")
		)
	)
	(footprint ""
		(layer "F.Cu")
		(at 393.1031 -185.748168)
		(property "Reference" "PC181"
			(at 0 0 0)
			(layer "F.SilkS")
			(hide yes)
			(effects
				(font
					(size 1.27 1.27)
				)
			)
		)
		(property "Value" ""
			(at 0 0 0)
			(layer "F.Fab")
			(effects
				(font
					(size 1.27 1.27)
				)
			)
		)
		(duplicate_pad_numbers_are_jumpers no)
		(fp_line
			(start -0.7874 -0.4064)
			(end 0.7874 -0.4064)
			(stroke
				(width 0.1524)
				(type default)
			)
			(layer "F.SilkS")
		)
		(fp_line
			(start -0.7874 0.4064)
			(end -0.7874 -0.4064)
			(stroke
				(width 0.1524)
				(type default)
			)
			(layer "F.SilkS")
		)
		(fp_line
			(start 0.7874 -0.4064)
			(end 0.7874 0.4064)
			(stroke
				(width 0.1524)
				(type default)
			)
			(layer "F.SilkS")
		)
		(fp_line
			(start 0.7874 0.4064)
			(end -0.7874 0.4064)
			(stroke
				(width 0.1524)
				(type default)
			)
			(layer "F.SilkS")
		)
		(fp_line
			(start -0.67945 -0.305054)
			(end -0.12065 -0.305054)
			(stroke
				(width 0.1)
				(type default)
			)
			(layer "F.Fab")
		)
		(fp_line
			(start -0.67945 0.3048)
			(end -0.67945 -0.305054)
			(stroke
				(width 0.1)
				(type default)
			)
			(layer "F.Fab")
		)
		(fp_line
			(start -0.12065 -0.305054)
			(end -0.12065 -0.2794)
			(stroke
				(width 0.1)
				(type default)
			)
			(layer "F.Fab")
		)
		(fp_line
			(start -0.12065 -0.2794)
			(end 0.12065 -0.2794)
			(stroke
				(width 0.1)
				(type default)
			)
			(layer "F.Fab")
		)
		(fp_line
			(start -0.12065 0.2794)
			(end -0.12065 0.3048)
			(stroke
				(width 0.1)
				(type default)
			)
			(layer "F.Fab")
		)
		(fp_line
			(start -0.12065 0.3048)
			(end -0.67945 0.3048)
			(stroke
				(width 0.1)
				(type default)
			)
			(layer "F.Fab")
		)
		(fp_line
			(start 0.120396 0.2794)
			(end -0.12065 0.2794)
			(stroke
				(width 0.1)
				(type default)
			)
			(layer "F.Fab")
		)
		(fp_line
			(start 0.120396 0.3048)
			(end 0.120396 0.2794)
			(stroke
				(width 0.1)
				(type default)
			)
			(layer "F.Fab")
		)
		(fp_line
			(start 0.12065 -0.3048)
			(end 0.67945 -0.3048)
			(stroke
				(width 0.1)
				(type default)
			)
			(layer "F.Fab")
		)
		(fp_line
			(start 0.12065 -0.2794)
			(end 0.12065 -0.3048)
			(stroke
				(width 0.1)
				(type default)
			)
			(layer "F.Fab")
		)
		(fp_line
			(start 0.67945 -0.3048)
			(end 0.67945 0.3048)
			(stroke
				(width 0.1)
				(type default)
			)
			(layer "F.Fab")
		)
		(fp_line
			(start 0.67945 0.3048)
			(end 0.120396 0.3048)
			(stroke
				(width 0.1)
				(type default)
			)
			(layer "F.Fab")
		)
		(pad "1" smd circle
			(at -0.40005 0)
			(size 0 0)
			(layers "F.Cu" "F.Mask" "F.Paste")
			(net "SW_PVDDCR_CPU0_P0_SW4")
		)
		(pad "2" smd circle
			(at 0.40005 0)
			(size 0 0)
			(layers "F.Cu" "F.Mask" "F.Paste")
			(net "SW_PVDDCR_CPU0_P0_SW4_RC")
		)
	)
)
